# T6G (Grand Teton) — schematic netlist excerpt (pin names and nets, part order shuffled) for the footprints in the layout excerpt that follows; sources: Cadence DE-HDL packaged netlist, KiCad conversion of 04192023_DAF0TMB3IC0_F0TG_MB_C_brd_V02_OCP.brd

C350  Q_CAP  0.1UF 10V 10% X7S  pkg C0201  page 334 : A = P0V9_CPU1_RT1_2A ; B = GND

U6020  TCA9548APWR  IC  pkg TSSOP24XA  page 184
  A0  = RT_SMB_MUX_ADDR0
  A1  = RT_SMB_MUX_ADDR1
  \reset#\  = RST_SMB_RT_N
  SD0  = SMB_RT_CPU1_P0_SDA
  SC0  = SMB_RT_CPU1_P0_SCL
  SD1  = SMB_RT_CPU1_P1_SDA
  SC1  = SMB_RT_CPU1_P1_SCL
  SD2  = SMB_RT_CPU1_P3_SDA
  SC2  = SMB_RT_CPU1_P3_SCL
  SD3  = SMB_RT_CPU1_P2_SDA
  SC3  = SMB_RT_CPU1_P2_SCL
  GND  = GND
  SD4  = SMB_RT_CPU0_P0_SDA
  SC4  = SMB_RT_CPU0_P0_SCL
  SD5  = SMB_RT_CPU0_P1_SDA
  SC5  = SMB_RT_CPU0_P1_SCL
  SD6  = SMB_RT_CPU0_P3_SDA
  SC6  = SMB_RT_CPU0_P3_SCL
  SD7  = SMB_RT_CPU0_P2_SDA
  SC7  = SMB_RT_CPU0_P2_SCL
  A2  = RT_SMB_MUX_ADDR2
  SCL  = SMB_MUX_RT_SCL
  SDA  = SMB_MUX_RT_SDA
  VCC  = P1V8_AUX

(kicad_pcb
	(version 20260206)
	(generator "pcbnew")
	(generator_version "10.0")
	(general
		(thickness 1.6)
		(legacy_teardrops no)
	)
	(paper "A4")
	(title_block
		(title "04192023_DAF0TMB3IC0_F0TG_MB_C_brd_V02_OCP.brd")
		(comment 1 "Grand Teton / footprints 6866-6867 of 8354")
	)
	(layers
		(0 "F.Cu" signal "TOP")
		(4 "In1.Cu" signal "GND")
		(6 "In2.Cu" signal "IN1")
		(8 "In3.Cu" signal "GND1")
		(10 "In4.Cu" signal "IN2")
		(12 "In5.Cu" signal "GND2")
		(14 "In6.Cu" signal "IN3")
		(16 "In7.Cu" signal "GND3")
		(18 "In8.Cu" signal "VCC")
		(20 "In9.Cu" signal "VCC1")
		(22 "In10.Cu" signal "GND4")
		(24 "In11.Cu" signal "IN4")
		(26 "In12.Cu" signal "GND5")
		(28 "In13.Cu" signal "IN5")
		(30 "In14.Cu" signal "GND6")
		(32 "In15.Cu" signal "IN6")
		(34 "In16.Cu" signal "GND7")
		(2 "B.Cu" signal "BOTTOM")
		(9 "F.Adhes" user "F.Adhesive")
		(11 "B.Adhes" user "B.Adhesive")
		(13 "F.Paste" user "Package Geometry/Pastemask Top")
		(15 "B.Paste" user "Package Geometry/Pastemask Bottom")
		(5 "F.SilkS" user "Ref Des/Silkscreen Top")
		(7 "B.SilkS" user "Ref Des/Silkscreen Bottom")
		(1 "F.Mask" user "Board Geometry/Soldermask Top")
		(3 "B.Mask" user "Board Geometry/Soldermask Bottom")
		(17 "Dwgs.User" user "User.Drawings")
		(19 "Cmts.User" user "User.Comments")
		(21 "Eco1.User" user "User.Eco1")
		(23 "Eco2.User" user "User.Eco2")
		(25 "Edge.Cuts" user "Board Geometry/Outline")
		(27 "Margin" user)
		(31 "F.CrtYd" user "Package Geometry/Place Bound Top")
		(29 "B.CrtYd" user "Package Geometry/Place Bound Bottom")
		(35 "F.Fab" user "Ref Des/Assembly Top")
		(33 "B.Fab" user "Ref Des/Assembly Bottom")
	)
	(footprint ""
		(layer "B.Cu")
		(at 224.310194 -336.846164 180)
		(property "Reference" "U6020"
			(at -1.980438 -5.745734 0)
			(unlocked yes)
			(layer "B.SilkS")
			(effects
				(font
					(size 0.7874 0.5842)
					(thickness 0.1524)
				)
				(justify left mirror)
			)
		)
		(property "Value" ""
			(at 0 0 0)
			(layer "B.Fab")
			(effects
				(font
					(size 1.27 1.27)
				)
				(justify mirror)
			)
		)
		(duplicate_pad_numbers_are_jumpers no)
		(fp_line
			(start 1.8542 3.949954)
			(end -1.8542 3.949954)
			(stroke
				(width 0.1524)
				(type default)
			)
			(layer "B.SilkS")
		)
		(fp_line
			(start 1.8542 -3.949954)
			(end 1.8542 3.949954)
			(stroke
				(width 0.1524)
				(type default)
			)
			(layer "B.SilkS")
		)
		(fp_line
			(start 1.282954 -3.949954)
			(end 1.8542 -3.949954)
			(stroke
				(width 0.1524)
				(type default)
			)
			(layer "B.SilkS")
		)
		(fp_line
			(start 0 -2.667)
			(end 1.282954 -3.949954)
			(stroke
				(width 0.1524)
				(type default)
			)
			(layer "B.SilkS")
		)
		(fp_line
			(start -1.282954 -3.949954)
			(end 0 -2.667)
			(stroke
				(width 0.1524)
				(type default)
			)
			(layer "B.SilkS")
		)
		(fp_line
			(start -1.8542 3.949954)
			(end -1.8542 -3.949954)
			(stroke
				(width 0.1524)
				(type default)
			)
			(layer "B.SilkS")
		)
		(fp_line
			(start -1.8542 -3.949954)
			(end -1.282954 -3.949954)
			(stroke
				(width 0.1524)
				(type default)
			)
			(layer "B.SilkS")
		)
		(fp_poly
			(pts
				(xy 2.737358 -5.05968) (xy 3.753358 -5.05968) (xy 3.245358 -4.04368)
			)
			(stroke
				(width 0)
				(type default)
			)
			(fill yes)
			(layer "B.SilkS")
		)
		(fp_line
			(start 2.249932 3.949954)
			(end -2.249932 3.949954)
			(stroke
				(width 0.1)
				(type default)
			)
			(layer "B.Fab")
		)
		(fp_line
			(start 2.249932 -3.949954)
			(end 2.249932 3.949954)
			(stroke
				(width 0.1)
				(type default)
			)
			(layer "B.Fab")
		)
		(fp_line
			(start -2.249932 3.949954)
			(end -2.249932 -3.949954)
			(stroke
				(width 0.1)
				(type default)
			)
			(layer "B.Fab")
		)
		(fp_line
			(start -2.249932 -3.949954)
			(end 2.249932 -3.949954)
			(stroke
				(width 0.1)
				(type default)
			)
			(layer "B.Fab")
		)
		(fp_poly
			(pts
				(xy 4.8006 -4.08305) (xy 4.8006 -3.06705) (xy 3.7846 -3.57505)
			)
			(stroke
				(width 0)
				(type default)
			)
			(fill yes)
			(layer "B.Fab")
		)
		(pad "1" smd rect
			(at 2.800096 -3.57505 90)
			(size 0.3048 1.6002)
			(layers "B.Cu" "B.Mask" "B.Paste")
			(net "RT_SMB_MUX_ADDR0")
		)
		(pad "2" smd rect
			(at 2.800096 -2.925064 90)
			(size 0.3048 1.6002)
			(layers "B.Cu" "B.Mask" "B.Paste")
			(net "RT_SMB_MUX_ADDR1")
		)
		(pad "3" smd rect
			(at 2.800096 -2.275078 90)
			(size 0.3048 1.6002)
			(layers "B.Cu" "B.Mask" "B.Paste")
			(net "RST_SMB_RT_N")
		)
		(pad "4" smd rect
			(at 2.800096 -1.625092 90)
			(size 0.3048 1.6002)
			(layers "B.Cu" "B.Mask" "B.Paste")
			(net "SMB_RT_CPU1_P0_SDA")
		)
		(pad "5" smd rect
			(at 2.800096 -0.975106 90)
			(size 0.3048 1.6002)
			(layers "B.Cu" "B.Mask" "B.Paste")
			(net "SMB_RT_CPU1_P0_SCL")
		)
		(pad "6" smd rect
			(at 2.800096 -0.32512 90)
			(size 0.3048 1.6002)
			(layers "B.Cu" "B.Mask" "B.Paste")
			(net "SMB_RT_CPU1_P1_SDA")
		)
		(pad "7" smd rect
			(at 2.800096 0.32512 90)
			(size 0.3048 1.6002)
			(layers "B.Cu" "B.Mask" "B.Paste")
			(net "SMB_RT_CPU1_P1_SCL")
		)
		(pad "8" smd rect
			(at 2.800096 0.975106 90)
			(size 0.3048 1.6002)
			(layers "B.Cu" "B.Mask" "B.Paste")
			(net "SMB_RT_CPU1_P3_SDA")
		)
		(pad "9" smd rect
			(at 2.800096 1.625092 90)
			(size 0.3048 1.6002)
			(layers "B.Cu" "B.Mask" "B.Paste")
			(net "SMB_RT_CPU1_P3_SCL")
		)
		(pad "10" smd rect
			(at 2.800096 2.275078 90)
			(size 0.3048 1.6002)
			(layers "B.Cu" "B.Mask" "B.Paste")
			(net "SMB_RT_CPU1_P2_SDA")
		)
		(pad "11" smd rect
			(at 2.800096 2.925064 90)
			(size 0.3048 1.6002)
			(layers "B.Cu" "B.Mask" "B.Paste")
			(net "SMB_RT_CPU1_P2_SCL")
		)
		(pad "12" smd rect
			(at 2.800096 3.57505 90)
			(size 0.3048 1.6002)
			(layers "B.Cu" "B.Mask" "B.Paste")
			(net "GND")
		)
		(pad "13" smd rect
			(at -2.800096 3.57505 90)
			(size 0.3048 1.6002)
			(layers "B.Cu" "B.Mask" "B.Paste")
			(net "SMB_RT_CPU0_P0_SDA")
		)
		(pad "14" smd rect
			(at -2.800096 2.925064 90)
			(size 0.3048 1.6002)
			(layers "B.Cu" "B.Mask" "B.Paste")
			(net "SMB_RT_CPU0_P0_SCL")
		)
		(pad "15" smd rect
			(at -2.800096 2.275078 90)
			(size 0.3048 1.6002)
			(layers "B.Cu" "B.Mask" "B.Paste")
			(net "SMB_RT_CPU0_P1_SDA")
		)
		(pad "16" smd rect
			(at -2.800096 1.625092 90)
			(size 0.3048 1.6002)
			(layers "B.Cu" "B.Mask" "B.Paste")
			(net "SMB_RT_CPU0_P1_SCL")
		)
		(pad "17" smd rect
			(at -2.800096 0.975106 90)
			(size 0.3048 1.6002)
			(layers "B.Cu" "B.Mask" "B.Paste")
			(net "SMB_RT_CPU0_P3_SDA")
		)
		(pad "18" smd rect
			(at -2.800096 0.32512 90)
			(size 0.3048 1.6002)
			(layers "B.Cu" "B.Mask" "B.Paste")
			(net "SMB_RT_CPU0_P3_SCL")
		)
		(pad "19" smd rect
			(at -2.800096 -0.32512 90)
			(size 0.3048 1.6002)
			(layers "B.Cu" "B.Mask" "B.Paste")
			(net "SMB_RT_CPU0_P2_SDA")
		)
		(pad "20" smd rect
			(at -2.800096 -0.975106 90)
			(size 0.3048 1.6002)
			(layers "B.Cu" "B.Mask" "B.Paste")
			(net "SMB_RT_CPU0_P2_SCL")
		)
		(pad "21" smd rect
			(at -2.800096 -1.625092 90)
			(size 0.3048 1.6002)
			(layers "B.Cu" "B.Mask" "B.Paste")
			(net "RT_SMB_MUX_ADDR2")
		)
		(pad "22" smd rect
			(at -2.800096 -2.275078 90)
			(size 0.3048 1.6002)
			(layers "B.Cu" "B.Mask" "B.Paste")
			(net "SMB_MUX_RT_SCL")
		)
		(pad "23" smd rect
			(at -2.800096 -2.925064 90)
			(size 0.3048 1.6002)
			(layers "B.Cu" "B.Mask" "B.Paste")
			(net "SMB_MUX_RT_SDA")
		)
		(pad "24" smd rect
			(at -2.800096 -3.57505 90)
			(size 0.3048 1.6002)
			(layers "B.Cu" "B.Mask" "B.Paste")
			(net "P1V8_AUX")
		)
	)
	(footprint ""
		(layer "B.Cu")
		(at 94.446344 -388.011162 -90)
		(property "Reference" "C350"
			(at 0 0 90)
			(layer "B.SilkS")
			(hide yes)
			(effects
				(font
					(size 1.27 1.27)
				)
				(justify mirror)
			)
		)
		(property "Value" ""
			(at 0 0 90)
			(layer "B.Fab")
			(effects
				(font
					(size 1.27 1.27)
				)
				(justify mirror)
			)
		)
		(duplicate_pad_numbers_are_jumpers no)
		(fp_line
			(start -0.299974 0.150114)
			(end 0.299974 0.150114)
			(stroke
				(width 0.1)
				(type default)
			)
			(layer "B.Fab")
		)
		(fp_line
			(start 0.299974 0.150114)
			(end 0.299974 -0.150114)
			(stroke
				(width 0.1)
				(type default)
			)
			(layer "B.Fab")
		)
		(fp_line
			(start -0.299974 -0.150114)
			(end -0.299974 0.150114)
			(stroke
				(width 0.1)
				(type default)
			)
			(layer "B.Fab")
		)
		(fp_line
			(start 0.299974 -0.150114)
			(end -0.299974 -0.150114)
			(stroke
				(width 0.1)
				(type default)
			)
			(layer "B.Fab")
		)
		(pad "1" smd rect
			(at 0.2667 0 90)
			(size 0.3048 0.381)
			(layers "B.Cu" "B.Mask" "B.Paste")
			(net "P0V9_CPU1_RT1_2A")
		)
		(pad "2" smd rect
			(at -0.2667 0 90)
			(size 0.3048 0.381)
			(layers "B.Cu" "B.Mask" "B.Paste")
			(net "GND")
		)
	)
)
